# SCM (Grand Teton) — schematic netlist excerpt (pin names and nets, part order shuffled) for the footprints in the layout excerpt that follows; sources: Cadence DE-HDL packaged netlist, KiCad conversion of 12092022_DA0F0TMDCD0_F0T_Management_Board_D_brd_V3_OCP.brd

R156  Q_RES  0 5% EMPTY  pkg 0402LF  page 13 : A = P2V5_AUX ; B = P3V3_P2V5_P1V8_RVDD
C298  Q_CAP  0.1UF 25V 10% X7R  pkg 0402  page 54 : A = P3V3_LDO ; B = GND

(kicad_pcb
	(version 20260206)
	(generator "pcbnew")
	(generator_version "10.0")
	(general
		(thickness 1.6)
		(legacy_teardrops no)
	)
	(paper "A4")
	(title_block
		(title "12092022_DA0F0TMDCD0_F0T_Management_Board_D_brd_V3_OCP.brd")
		(comment 1 "Grand Teton / footprints 364-365 of 1440")
	)
	(layers
		(0 "F.Cu" signal "TOP")
		(4 "In1.Cu" signal "GND")
		(6 "In2.Cu" signal "IN1")
		(8 "In3.Cu" signal "GND1")
		(10 "In4.Cu" signal "IN2")
		(12 "In5.Cu" signal "VCC")
		(14 "In6.Cu" signal "VCC1")
		(16 "In7.Cu" signal "IN3")
		(18 "In8.Cu" signal "GND2")
		(20 "In9.Cu" signal "IN4")
		(22 "In10.Cu" signal "GND3")
		(2 "B.Cu" signal "BOTTOM")
		(9 "F.Adhes" user "F.Adhesive")
		(11 "B.Adhes" user "B.Adhesive")
		(13 "F.Paste" user "Package Geometry/Pastemask Top")
		(15 "B.Paste" user "Package Geometry/Pastemask Bottom")
		(5 "F.SilkS" user "Ref Des/Silkscreen Top")
		(7 "B.SilkS" user "Ref Des/Silkscreen Bottom")
		(1 "F.Mask" user "Board Geometry/Soldermask Top")
		(3 "B.Mask" user "Board Geometry/Soldermask Bottom")
		(17 "Dwgs.User" user "User.Drawings")
		(19 "Cmts.User" user "User.Comments")
		(21 "Eco1.User" user "User.Eco1")
		(23 "Eco2.User" user "User.Eco2")
		(25 "Edge.Cuts" user "Board Geometry/Outline")
		(27 "Margin" user)
		(31 "F.CrtYd" user "Package Geometry/Place Bound Top")
		(29 "B.CrtYd" user "Package Geometry/Place Bound Bottom")
		(35 "F.Fab" user "Ref Des/Assembly Top")
		(33 "B.Fab" user "Ref Des/Assembly Bottom")
	)
	(footprint ""
		(layer "F.Cu")
		(at 40.756078 -36.578286 90)
		(property "Reference" "R156"
			(at 0 0 90)
			(layer "F.SilkS")
			(hide yes)
			(effects
				(font
					(size 1.27 1.27)
				)
			)
		)
		(property "Value" ""
			(at 0 0 90)
			(layer "F.Fab")
			(effects
				(font
					(size 1.27 1.27)
				)
			)
		)
		(duplicate_pad_numbers_are_jumpers no)
		(fp_line
			(start 0.7874 -0.4064)
			(end 0.7874 0.4064)
			(stroke
				(width 0.1524)
				(type default)
			)
			(layer "F.SilkS")
		)
		(fp_line
			(start -0.7874 -0.4064)
			(end 0.7874 -0.4064)
			(stroke
				(width 0.1524)
				(type default)
			)
			(layer "F.SilkS")
		)
		(fp_line
			(start 0.7874 0.4064)
			(end -0.7874 0.4064)
			(stroke
				(width 0.1524)
				(type default)
			)
			(layer "F.SilkS")
		)
		(fp_line
			(start -0.7874 0.4064)
			(end -0.7874 -0.4064)
			(stroke
				(width 0.1524)
				(type default)
			)
			(layer "F.SilkS")
		)
		(fp_line
			(start -0.12065 -0.305054)
			(end -0.12065 -0.2794)
			(stroke
				(width 0.1)
				(type default)
			)
			(layer "F.Fab")
		)
		(fp_line
			(start -0.67945 -0.305054)
			(end -0.12065 -0.305054)
			(stroke
				(width 0.1)
				(type default)
			)
			(layer "F.Fab")
		)
		(fp_line
			(start 0.67945 -0.3048)
			(end 0.67945 0.3048)
			(stroke
				(width 0.1)
				(type default)
			)
			(layer "F.Fab")
		)
		(fp_line
			(start 0.12065 -0.3048)
			(end 0.67945 -0.3048)
			(stroke
				(width 0.1)
				(type default)
			)
			(layer "F.Fab")
		)
		(fp_line
			(start 0.12065 -0.2794)
			(end 0.12065 -0.3048)
			(stroke
				(width 0.1)
				(type default)
			)
			(layer "F.Fab")
		)
		(fp_line
			(start -0.12065 -0.2794)
			(end 0.12065 -0.2794)
			(stroke
				(width 0.1)
				(type default)
			)
			(layer "F.Fab")
		)
		(fp_line
			(start 0.120396 0.2794)
			(end -0.12065 0.2794)
			(stroke
				(width 0.1)
				(type default)
			)
			(layer "F.Fab")
		)
		(fp_line
			(start -0.12065 0.2794)
			(end -0.12065 0.3048)
			(stroke
				(width 0.1)
				(type default)
			)
			(layer "F.Fab")
		)
		(fp_line
			(start 0.67945 0.3048)
			(end 0.120396 0.3048)
			(stroke
				(width 0.1)
				(type default)
			)
			(layer "F.Fab")
		)
		(fp_line
			(start 0.120396 0.3048)
			(end 0.120396 0.2794)
			(stroke
				(width 0.1)
				(type default)
			)
			(layer "F.Fab")
		)
		(fp_line
			(start -0.12065 0.3048)
			(end -0.67945 0.3048)
			(stroke
				(width 0.1)
				(type default)
			)
			(layer "F.Fab")
		)
		(fp_line
			(start -0.67945 0.3048)
			(end -0.67945 -0.305054)
			(stroke
				(width 0.1)
				(type default)
			)
			(layer "F.Fab")
		)
		(pad "1" smd circle
			(at -0.40005 0 90)
			(size 0 0)
			(layers "F.Cu" "F.Mask" "F.Paste")
			(net "P2V5_AUX")
		)
		(pad "2" smd circle
			(at 0.40005 0 90)
			(size 0 0)
			(layers "F.Cu" "F.Mask" "F.Paste")
			(net "P3V3_P2V5_P1V8_RVDD")
		)
	)
	(footprint ""
		(layer "F.Cu")
		(at 33.528 -64.4398 180)
		(property "Reference" "C298"
			(at 0 0 180)
			(layer "F.SilkS")
			(hide yes)
			(effects
				(font
					(size 1.27 1.27)
				)
			)
		)
		(property "Value" ""
			(at 0 0 180)
			(layer "F.Fab")
			(effects
				(font
					(size 1.27 1.27)
				)
			)
		)
		(duplicate_pad_numbers_are_jumpers no)
		(fp_line
			(start 0.7874 0.4064)
			(end -0.7874 0.4064)
			(stroke
				(width 0.1524)
				(type default)
			)
			(layer "F.SilkS")
		)
		(fp_line
			(start 0.7874 -0.4064)
			(end 0.7874 0.4064)
			(stroke
				(width 0.1524)
				(type default)
			)
			(layer "F.SilkS")
		)
		(fp_line
			(start -0.7874 0.4064)
			(end -0.7874 -0.4064)
			(stroke
				(width 0.1524)
				(type default)
			)
			(layer "F.SilkS")
		)
		(fp_line
			(start -0.7874 -0.4064)
			(end 0.7874 -0.4064)
			(stroke
				(width 0.1524)
				(type default)
			)
			(layer "F.SilkS")
		)
		(fp_line
			(start 0.67945 0.3048)
			(end 0.120396 0.3048)
			(stroke
				(width 0.1)
				(type default)
			)
			(layer "F.Fab")
		)
		(fp_line
			(start 0.67945 -0.3048)
			(end 0.67945 0.3048)
			(stroke
				(width 0.1)
				(type default)
			)
			(layer "F.Fab")
		)
		(fp_line
			(start 0.12065 -0.2794)
			(end 0.12065 -0.3048)
			(stroke
				(width 0.1)
				(type default)
			)
			(layer "F.Fab")
		)
		(fp_line
			(start 0.12065 -0.3048)
			(end 0.67945 -0.3048)
			(stroke
				(width 0.1)
				(type default)
			)
			(layer "F.Fab")
		)
		(fp_line
			(start 0.120396 0.3048)
			(end 0.120396 0.2794)
			(stroke
				(width 0.1)
				(type default)
			)
			(layer "F.Fab")
		)
		(fp_line
			(start 0.120396 0.2794)
			(end -0.12065 0.2794)
			(stroke
				(width 0.1)
				(type default)
			)
			(layer "F.Fab")
		)
		(fp_line
			(start -0.12065 0.3048)
			(end -0.67945 0.3048)
			(stroke
				(width 0.1)
				(type default)
			)
			(layer "F.Fab")
		)
		(fp_line
			(start -0.12065 0.2794)
			(end -0.12065 0.3048)
			(stroke
				(width 0.1)
				(type default)
			)
			(layer "F.Fab")
		)
		(fp_line
			(start -0.12065 -0.2794)
			(end 0.12065 -0.2794)
			(stroke
				(width 0.1)
				(type default)
			)
			(layer "F.Fab")
		)
		(fp_line
			(start -0.12065 -0.305054)
			(end -0.12065 -0.2794)
			(stroke
				(width 0.1)
				(type default)
			)
			(layer "F.Fab")
		)
		(fp_line
			(start -0.67945 0.3048)
			(end -0.67945 -0.305054)
			(stroke
				(width 0.1)
				(type default)
			)
			(layer "F.Fab")
		)
		(fp_line
			(start -0.67945 -0.305054)
			(end -0.12065 -0.305054)
			(stroke
				(width 0.1)
				(type default)
			)
			(layer "F.Fab")
		)
		(pad "1" smd circle
			(at -0.40005 0 180)
			(size 0 0)
			(layers "F.Cu" "F.Mask" "F.Paste")
			(net "P3V3_LDO")
		)
		(pad "2" smd circle
			(at 0.40005 0 180)
			(size 0 0)
			(layers "F.Cu" "F.Mask" "F.Paste")
			(net "GND")
		)
	)
)
